# BASEBOARD_FAB2 (Tioga Pass) — schematic netlist excerpt (pin names and nets, part order shuffled) for the footprints in the layout excerpt that follows; sources: Cadence DE-HDL packaged netlist, KiCad conversion of Wiwynn_Tioga_Pass_MB.brd

R4D21  RES  27.4 1% CHIP  pkg 0402  page 103 : A = CLK_100M_CPU1_RC_REFCLK0_R_DN ; B = CLK_100M_CPU1_RC_REFCLK0_DN
C4E26  CAP  1.0UF 16V 10% X6S  pkg 0402  page 202 : A = VR_PVCCIN_CPU0_PH2_VCIN ; B = GND
C1B5  CAP_A  0.1UF 16V 10% X7R  pkg 0402V  page 226 : A = VR_PVDDQ_KLM_VDD ; B = GND

(kicad_pcb
	(version 20260206)
	(generator "pcbnew")
	(generator_version "10.0")
	(general
		(thickness 1.6)
		(legacy_teardrops no)
	)
	(paper "A4")
	(title_block
		(title "Wiwynn_Tioga_Pass_MB.brd")
		(comment 1 "Tioga Pass / footprints 2213-2215 of 4770")
	)
	(layers
		(0 "F.Cu" signal "TOP")
		(4 "In1.Cu" signal "L2GND")
		(6 "In2.Cu" signal "L3")
		(8 "In3.Cu" signal "L4GND")
		(10 "In4.Cu" signal "L5")
		(12 "In5.Cu" signal "L6GND")
		(14 "In6.Cu" signal "L7VCC")
		(16 "In7.Cu" signal "L8VCC")
		(18 "In8.Cu" signal "L9GND")
		(20 "In9.Cu" signal "L10")
		(22 "In10.Cu" signal "L11GND")
		(24 "In11.Cu" signal "L12")
		(26 "In12.Cu" signal "L13GND")
		(2 "B.Cu" signal "BOTTOM")
		(9 "F.Adhes" user "F.Adhesive")
		(11 "B.Adhes" user "B.Adhesive")
		(13 "F.Paste" user "Package Geometry/Pastemask Top")
		(15 "B.Paste" user "Package Geometry/Pastemask Bottom")
		(5 "F.SilkS" user "Ref Des/Silkscreen Top")
		(7 "B.SilkS" user "Ref Des/Silkscreen Bottom")
		(1 "F.Mask" user "Board Geometry/Soldermask Top")
		(3 "B.Mask" user "Board Geometry/Soldermask Bottom")
		(17 "Dwgs.User" user "User.Drawings")
		(19 "Cmts.User" user "User.Comments")
		(21 "Eco1.User" user "User.Eco1")
		(23 "Eco2.User" user "User.Eco2")
		(25 "Edge.Cuts" user "Board Geometry/Outline")
		(27 "Margin" user)
		(31 "F.CrtYd" user "Package Geometry/Place Bound Top")
		(29 "B.CrtYd" user "Package Geometry/Place Bound Bottom")
		(35 "F.Fab" user "Ref Des/Assembly Top")
		(33 "B.Fab" user "Ref Des/Assembly Bottom")
	)
	(footprint ""
		(layer "F.Cu")
		(at 163.576 -79.248 -90)
		(property "Reference" "R4D21"
			(at 0 0 270)
			(layer "F.SilkS")
			(hide yes)
			(effects
				(font
					(size 1.27 1.27)
				)
			)
		)
		(property "Value" ""
			(at 0 0 270)
			(layer "F.Fab")
			(effects
				(font
					(size 1.27 1.27)
				)
			)
		)
		(duplicate_pad_numbers_are_jumpers no)
		(fp_poly
			(pts
				(xy -0.2794 -0.1016) (xy 0.2794 -0.1016) (xy 0.2794 0.9906) (xy -0.2794 0.9906)
			)
			(stroke
				(width 0)
				(type default)
			)
			(fill no)
			(layer "F.CrtYd")
		)
		(fp_line
			(start -0.2794 0.9906)
			(end 0.2794 0.9906)
			(stroke
				(width 0.1)
				(type default)
			)
			(layer "F.Fab")
		)
		(fp_line
			(start 0.2794 0.9906)
			(end 0.2794 -0.1016)
			(stroke
				(width 0.1)
				(type default)
			)
			(layer "F.Fab")
		)
		(fp_line
			(start -0.2794 -0.1016)
			(end -0.2794 0.9906)
			(stroke
				(width 0.1)
				(type default)
			)
			(layer "F.Fab")
		)
		(fp_line
			(start 0.2794 -0.1016)
			(end -0.2794 -0.1016)
			(stroke
				(width 0.1)
				(type default)
			)
			(layer "F.Fab")
		)
		(pad "1" smd rect
			(at 0 0 270)
			(size 0.508 0.508)
			(layers "F.Cu" "F.Mask" "F.Paste")
			(net "CLK_100M_CPU1_RC_REFCLK0_R_DN")
		)
		(pad "2" smd rect
			(at 0 0.889 270)
			(size 0.508 0.508)
			(layers "F.Cu" "F.Mask" "F.Paste")
			(net "CLK_100M_CPU1_RC_REFCLK0_DN")
		)
		(zone
			(layer "F.Cu")
			(hatch none 0.5)
			(connect_pads
				(clearance 0)
			)
			(min_thickness 0.25)
			(keepout
				(tracks not_allowed)
				(vias allowed)
				(pads allowed)
				(copperpour not_allowed)
				(footprints allowed)
			)
			(placement
				(enabled no)
				(sheetname "")
			)
			(fill
				(thermal_gap 0.5)
				(thermal_bridge_width 0.5)
				(island_removal_mode 0)
			)
			(polygon
				(pts
					(xy 162.941 -79.502) (xy 162.941 -78.994) (xy 163.322 -78.994) (xy 163.322 -79.502)
				)
			)
		)
		(zone
			(layer "F.Cu")
			(hatch none 0.5)
			(connect_pads
				(clearance 0)
			)
			(min_thickness 0.25)
			(keepout
				(tracks allowed)
				(vias not_allowed)
				(pads allowed)
				(copperpour not_allowed)
				(footprints allowed)
			)
			(placement
				(enabled no)
				(sheetname "")
			)
			(fill
				(thermal_gap 0.5)
				(thermal_bridge_width 0.5)
				(island_removal_mode 0)
			)
			(polygon
				(pts
					(xy 163.322 -79.502) (xy 163.322 -78.994) (xy 162.941 -78.994) (xy 162.941 -79.502)
				)
			)
		)
	)
	(footprint ""
		(layer "F.Cu")
		(at 197.066154 -61.205364 -90)
		(property "Reference" "C4E26"
			(at 0 0 270)
			(layer "F.SilkS")
			(hide yes)
			(effects
				(font
					(size 1.27 1.27)
				)
			)
		)
		(property "Value" ""
			(at 0 0 270)
			(layer "F.Fab")
			(effects
				(font
					(size 1.27 1.27)
				)
			)
		)
		(duplicate_pad_numbers_are_jumpers no)
		(fp_poly
			(pts
				(xy 0.3048 -0.1016) (xy 0.3048 0.9906) (xy -0.3048 0.9906) (xy -0.3048 -0.1016)
			)
			(stroke
				(width 0)
				(type default)
			)
			(fill no)
			(layer "F.CrtYd")
		)
		(fp_line
			(start -0.3048 0.9906)
			(end 0.3048 0.9906)
			(stroke
				(width 0.1)
				(type default)
			)
			(layer "F.Fab")
		)
		(fp_line
			(start 0.3048 0.9906)
			(end 0.3048 -0.1016)
			(stroke
				(width 0.1)
				(type default)
			)
			(layer "F.Fab")
		)
		(fp_line
			(start -0.3048 -0.1016)
			(end -0.3048 0.9906)
			(stroke
				(width 0.1)
				(type default)
			)
			(layer "F.Fab")
		)
		(fp_line
			(start 0.3048 -0.1016)
			(end -0.3048 -0.1016)
			(stroke
				(width 0.1)
				(type default)
			)
			(layer "F.Fab")
		)
		(pad "1" smd rect
			(at 0 0 270)
			(size 0.508 0.508)
			(layers "F.Cu" "F.Mask" "F.Paste")
			(net "VR_PVCCIN_CPU0_PH2_VCIN")
		)
		(pad "2" smd rect
			(at 0 0.889 270)
			(size 0.508 0.508)
			(layers "F.Cu" "F.Mask" "F.Paste")
			(net "GND")
		)
		(zone
			(layer "F.Cu")
			(hatch none 0.5)
			(connect_pads
				(clearance 0)
			)
			(min_thickness 0.25)
			(keepout
				(tracks not_allowed)
				(vias allowed)
				(pads allowed)
				(copperpour not_allowed)
				(footprints allowed)
			)
			(placement
				(enabled no)
				(sheetname "")
			)
			(fill
				(thermal_gap 0.5)
				(thermal_bridge_width 0.5)
				(island_removal_mode 0)
			)
			(polygon
				(pts
					(xy 196.431154 -61.459364) (xy 196.431154 -60.951364) (xy 196.812154 -60.951364) (xy 196.812154 -61.459364)
				)
			)
		)
		(zone
			(layer "F.Cu")
			(hatch none 0.5)
			(connect_pads
				(clearance 0)
			)
			(min_thickness 0.25)
			(keepout
				(tracks allowed)
				(vias not_allowed)
				(pads allowed)
				(copperpour not_allowed)
				(footprints allowed)
			)
			(placement
				(enabled no)
				(sheetname "")
			)
			(fill
				(thermal_gap 0.5)
				(thermal_bridge_width 0.5)
				(island_removal_mode 0)
			)
			(polygon
				(pts
					(xy 196.812154 -61.459364) (xy 196.812154 -60.951364) (xy 196.431154 -60.951364) (xy 196.431154 -61.459364)
				)
			)
		)
	)
	(footprint ""
		(layer "F.Cu")
		(at 6.0452 -130.302 180)
		(property "Reference" "C1B5"
			(at -0.8382 -0.67818 180)
			(unlocked yes)
			(layer "F.SilkS")
			(effects
				(font
					(size 0.4064 0.254)
					(thickness 0.1524)
				)
				(justify left)
			)
		)
		(property "Value" ""
			(at 0 0 180)
			(layer "F.Fab")
			(effects
				(font
					(size 1.27 1.27)
				)
			)
		)
		(duplicate_pad_numbers_are_jumpers no)
		(fp_poly
			(pts
				(xy 0.3048 -0.1016) (xy 0.3048 0.9906) (xy -0.3048 0.9906) (xy -0.3048 -0.1016)
			)
			(stroke
				(width 0)
				(type default)
			)
			(fill no)
			(layer "F.CrtYd")
		)
		(fp_line
			(start 0.3048 0.9906)
			(end 0.3048 -0.1016)
			(stroke
				(width 0.1)
				(type default)
			)
			(layer "F.Fab")
		)
		(fp_line
			(start 0.3048 -0.1016)
			(end -0.3048 -0.1016)
			(stroke
				(width 0.1)
				(type default)
			)
			(layer "F.Fab")
		)
		(fp_line
			(start -0.3048 0.9906)
			(end 0.3048 0.9906)
			(stroke
				(width 0.1)
				(type default)
			)
			(layer "F.Fab")
		)
		(fp_line
			(start -0.3048 -0.1016)
			(end -0.3048 0.9906)
			(stroke
				(width 0.1)
				(type default)
			)
			(layer "F.Fab")
		)
		(pad "1" smd rect
			(at 0 0 180)
			(size 0.508 0.508)
			(layers "F.Cu" "F.Mask" "F.Paste")
			(net "VR_PVDDQ_KLM_VDD")
		)
		(pad "2" smd rect
			(at 0 0.889 180)
			(size 0.508 0.508)
			(layers "F.Cu" "F.Mask" "F.Paste")
			(net "GND")
		)
		(zone
			(layer "F.Cu")
			(hatch none 0.5)
			(connect_pads
				(clearance 0)
			)
			(min_thickness 0.25)
			(keepout
				(tracks not_allowed)
				(vias allowed)
				(pads allowed)
				(copperpour not_allowed)
				(footprints allowed)
			)
			(placement
				(enabled no)
				(sheetname "")
			)
			(fill
				(thermal_gap 0.5)
				(thermal_bridge_width 0.5)
				(island_removal_mode 0)
			)
			(polygon
				(pts
					(xy 6.2992 -130.937) (xy 5.7912 -130.937) (xy 5.7912 -130.556) (xy 6.2992 -130.556)
				)
			)
		)
		(zone
			(layer "F.Cu")
			(hatch none 0.5)
			(connect_pads
				(clearance 0)
			)
			(min_thickness 0.25)
			(keepout
				(tracks allowed)
				(vias not_allowed)
				(pads allowed)
				(copperpour not_allowed)
				(footprints allowed)
			)
			(placement
				(enabled no)
				(sheetname "")
			)
			(fill
				(thermal_gap 0.5)
				(thermal_bridge_width 0.5)
				(island_removal_mode 0)
			)
			(polygon
				(pts
					(xy 6.2992 -130.556) (xy 5.7912 -130.556) (xy 5.7912 -130.937) (xy 6.2992 -130.937)
				)
			)
		)
	)
)
